# S9S_MB_2U (Grand Teton) — schematic netlist excerpt (pin names and nets, part order shuffled) for the footprints in the layout excerpt that follows; sources: Cadence DE-HDL packaged netlist, KiCad conversion of 03242023_DA0F0TMBIJ0_F0T_Motherboard_J_brd_V01_OCP.brd

PR1311  Q_RES  0 5% CHIP  pkg 0402LF  page 278 : A = PVCCD_HV_CPU0_ISYS_R ; B = GND
R998  Q_RES  0 5% CHIP  pkg 0402LF  page 235 : A = FM_SMB_PEHPCPU0_PCIE_ALERT_N ; B = FM_SMB_PEHPCPU0_PCIE_ALERT_R_N

(kicad_pcb
	(version 20260206)
	(generator "pcbnew")
	(generator_version "10.0")
	(general
		(thickness 1.6)
		(legacy_teardrops no)
	)
	(paper "A4")
	(title_block
		(title "03242023_DA0F0TMBIJ0_F0T_Motherboard_J_brd_V01_OCP.brd")
		(comment 1 "Grand Teton / footprints 4969-4970 of 6105")
	)
	(layers
		(0 "F.Cu" signal "TOP")
		(4 "In1.Cu" signal "GND")
		(6 "In2.Cu" signal "IN1")
		(8 "In3.Cu" signal "GND1")
		(10 "In4.Cu" signal "IN2")
		(12 "In5.Cu" signal "GND2")
		(14 "In6.Cu" signal "IN3")
		(16 "In7.Cu" signal "GND3")
		(18 "In8.Cu" signal "VCC")
		(20 "In9.Cu" signal "VCC1")
		(22 "In10.Cu" signal "GND4")
		(24 "In11.Cu" signal "IN4")
		(26 "In12.Cu" signal "GND5")
		(28 "In13.Cu" signal "IN5")
		(30 "In14.Cu" signal "GND6")
		(32 "In15.Cu" signal "IN6")
		(34 "In16.Cu" signal "GND7")
		(2 "B.Cu" signal "BOTTOM")
		(9 "F.Adhes" user "F.Adhesive")
		(11 "B.Adhes" user "B.Adhesive")
		(13 "F.Paste" user "Package Geometry/Pastemask Top")
		(15 "B.Paste" user "Package Geometry/Pastemask Bottom")
		(5 "F.SilkS" user "Ref Des/Silkscreen Top")
		(7 "B.SilkS" user "Ref Des/Silkscreen Bottom")
		(1 "F.Mask" user "Board Geometry/Soldermask Top")
		(3 "B.Mask" user "Board Geometry/Soldermask Bottom")
		(17 "Dwgs.User" user "User.Drawings")
		(19 "Cmts.User" user "User.Comments")
		(21 "Eco1.User" user "User.Eco1")
		(23 "Eco2.User" user "User.Eco2")
		(25 "Edge.Cuts" user "Board Geometry/Outline")
		(27 "Margin" user)
		(31 "F.CrtYd" user "Package Geometry/Place Bound Top")
		(29 "B.CrtYd" user "Package Geometry/Place Bound Bottom")
		(35 "F.Fab" user "Ref Des/Assembly Top")
		(33 "B.Fab" user "Ref Des/Assembly Bottom")
	)
	(footprint ""
		(layer "B.Cu")
		(at 362.7374 -183.373776 180)
		(property "Reference" "R998"
			(at 0 0 0)
			(layer "B.SilkS")
			(hide yes)
			(effects
				(font
					(size 1.27 1.27)
				)
				(justify mirror)
			)
		)
		(property "Value" ""
			(at 0 0 0)
			(layer "B.Fab")
			(effects
				(font
					(size 1.27 1.27)
				)
				(justify mirror)
			)
		)
		(duplicate_pad_numbers_are_jumpers no)
		(fp_line
			(start 0.7874 0.4064)
			(end 0.7874 -0.4064)
			(stroke
				(width 0.1524)
				(type default)
			)
			(layer "B.SilkS")
		)
		(fp_line
			(start 0.7874 -0.4064)
			(end -0.7874 -0.4064)
			(stroke
				(width 0.1524)
				(type default)
			)
			(layer "B.SilkS")
		)
		(fp_line
			(start -0.7874 0.4064)
			(end 0.7874 0.4064)
			(stroke
				(width 0.1524)
				(type default)
			)
			(layer "B.SilkS")
		)
		(fp_line
			(start -0.7874 -0.4064)
			(end -0.7874 0.4064)
			(stroke
				(width 0.1524)
				(type default)
			)
			(layer "B.SilkS")
		)
		(fp_line
			(start 0.67945 0.3048)
			(end 0.67945 -0.305054)
			(stroke
				(width 0.1)
				(type default)
			)
			(layer "B.Fab")
		)
		(fp_line
			(start 0.67945 -0.305054)
			(end 0.12065 -0.305054)
			(stroke
				(width 0.1)
				(type default)
			)
			(layer "B.Fab")
		)
		(fp_line
			(start 0.12065 0.3048)
			(end 0.67945 0.3048)
			(stroke
				(width 0.1)
				(type default)
			)
			(layer "B.Fab")
		)
		(fp_line
			(start 0.12065 0.2794)
			(end 0.12065 0.3048)
			(stroke
				(width 0.1)
				(type default)
			)
			(layer "B.Fab")
		)
		(fp_line
			(start 0.12065 -0.2794)
			(end -0.12065 -0.2794)
			(stroke
				(width 0.1)
				(type default)
			)
			(layer "B.Fab")
		)
		(fp_line
			(start 0.12065 -0.305054)
			(end 0.12065 -0.2794)
			(stroke
				(width 0.1)
				(type default)
			)
			(layer "B.Fab")
		)
		(fp_line
			(start -0.120396 0.3048)
			(end -0.120396 0.2794)
			(stroke
				(width 0.1)
				(type default)
			)
			(layer "B.Fab")
		)
		(fp_line
			(start -0.120396 0.2794)
			(end 0.12065 0.2794)
			(stroke
				(width 0.1)
				(type default)
			)
			(layer "B.Fab")
		)
		(fp_line
			(start -0.12065 -0.2794)
			(end -0.12065 -0.3048)
			(stroke
				(width 0.1)
				(type default)
			)
			(layer "B.Fab")
		)
		(fp_line
			(start -0.12065 -0.3048)
			(end -0.67945 -0.3048)
			(stroke
				(width 0.1)
				(type default)
			)
			(layer "B.Fab")
		)
		(fp_line
			(start -0.67945 0.3048)
			(end -0.120396 0.3048)
			(stroke
				(width 0.1)
				(type default)
			)
			(layer "B.Fab")
		)
		(fp_line
			(start -0.67945 -0.3048)
			(end -0.67945 0.3048)
			(stroke
				(width 0.1)
				(type default)
			)
			(layer "B.Fab")
		)
		(pad "1" smd circle
			(at 0.40005 0)
			(size 0 0)
			(layers "B.Cu" "B.Mask" "B.Paste")
			(net "FM_SMB_PEHPCPU0_PCIE_ALERT_N")
		)
		(pad "2" smd circle
			(at -0.40005 0)
			(size 0 0)
			(layers "B.Cu" "B.Mask" "B.Paste")
			(net "FM_SMB_PEHPCPU0_PCIE_ALERT_R_N")
		)
	)
	(footprint ""
		(layer "B.Cu")
		(at 430.577244 -123.648724 180)
		(property "Reference" "PR1311"
			(at 0 0 0)
			(layer "B.SilkS")
			(hide yes)
			(effects
				(font
					(size 1.27 1.27)
				)
				(justify mirror)
			)
		)
		(property "Value" ""
			(at 0 0 0)
			(layer "B.Fab")
			(effects
				(font
					(size 1.27 1.27)
				)
				(justify mirror)
			)
		)
		(duplicate_pad_numbers_are_jumpers no)
		(fp_line
			(start 0.7874 0.4064)
			(end 0.7874 -0.4064)
			(stroke
				(width 0.1524)
				(type default)
			)
			(layer "B.SilkS")
		)
		(fp_line
			(start 0.7874 -0.4064)
			(end -0.7874 -0.4064)
			(stroke
				(width 0.1524)
				(type default)
			)
			(layer "B.SilkS")
		)
		(fp_line
			(start -0.7874 0.4064)
			(end 0.7874 0.4064)
			(stroke
				(width 0.1524)
				(type default)
			)
			(layer "B.SilkS")
		)
		(fp_line
			(start -0.7874 -0.4064)
			(end -0.7874 0.4064)
			(stroke
				(width 0.1524)
				(type default)
			)
			(layer "B.SilkS")
		)
		(fp_line
			(start 0.67945 0.3048)
			(end 0.67945 -0.305054)
			(stroke
				(width 0.1)
				(type default)
			)
			(layer "B.Fab")
		)
		(fp_line
			(start 0.67945 -0.305054)
			(end 0.12065 -0.305054)
			(stroke
				(width 0.1)
				(type default)
			)
			(layer "B.Fab")
		)
		(fp_line
			(start 0.12065 0.3048)
			(end 0.67945 0.3048)
			(stroke
				(width 0.1)
				(type default)
			)
			(layer "B.Fab")
		)
		(fp_line
			(start 0.12065 0.2794)
			(end 0.12065 0.3048)
			(stroke
				(width 0.1)
				(type default)
			)
			(layer "B.Fab")
		)
		(fp_line
			(start 0.12065 -0.2794)
			(end -0.12065 -0.2794)
			(stroke
				(width 0.1)
				(type default)
			)
			(layer "B.Fab")
		)
		(fp_line
			(start 0.12065 -0.305054)
			(end 0.12065 -0.2794)
			(stroke
				(width 0.1)
				(type default)
			)
			(layer "B.Fab")
		)
		(fp_line
			(start -0.120396 0.3048)
			(end -0.120396 0.2794)
			(stroke
				(width 0.1)
				(type default)
			)
			(layer "B.Fab")
		)
		(fp_line
			(start -0.120396 0.2794)
			(end 0.12065 0.2794)
			(stroke
				(width 0.1)
				(type default)
			)
			(layer "B.Fab")
		)
		(fp_line
			(start -0.12065 -0.2794)
			(end -0.12065 -0.3048)
			(stroke
				(width 0.1)
				(type default)
			)
			(layer "B.Fab")
		)
		(fp_line
			(start -0.12065 -0.3048)
			(end -0.67945 -0.3048)
			(stroke
				(width 0.1)
				(type default)
			)
			(layer "B.Fab")
		)
		(fp_line
			(start -0.67945 0.3048)
			(end -0.120396 0.3048)
			(stroke
				(width 0.1)
				(type default)
			)
			(layer "B.Fab")
		)
		(fp_line
			(start -0.67945 -0.3048)
			(end -0.67945 0.3048)
			(stroke
				(width 0.1)
				(type default)
			)
			(layer "B.Fab")
		)
		(pad "1" smd circle
			(at 0.40005 0)
			(size 0 0)
			(layers "B.Cu" "B.Mask" "B.Paste")
			(net "PVCCD_HV_CPU0_ISYS_R")
		)
		(pad "2" smd circle
			(at -0.40005 0)
			(size 0 0)
			(layers "B.Cu" "B.Mask" "B.Paste")
			(net "GND")
		)
	)
)
